(kicad_pcb
	(version 20260206)
	(generator "pcbnew")
	(generator_version "10.0")
	(general
		(thickness 1.6)
		(legacy_teardrops no)
	)
	(paper "A4")
	(title_block
		(title "baseboard — 13948-1b.1110WZS1818.brd")
		(comment 1 "Honey Badger (Wiwynn) / footprints 2063-2071 of 2523")
	)
	(layers
		(0 "F.Cu" signal "TOP")
		(4 "In1.Cu" signal "L2GND")
		(6 "In2.Cu" signal "L3")
		(8 "In3.Cu" signal "L4VCC")
		(10 "In4.Cu" signal "L5VCC")
		(12 "In5.Cu" signal "L6")
		(14 "In6.Cu" signal "L7GND")
		(2 "B.Cu" signal "BOTTOM")
		(9 "F.Adhes" user "F.Adhesive")
		(11 "B.Adhes" user "B.Adhesive")
		(13 "F.Paste" user "Package Geometry/Pastemask Top")
		(15 "B.Paste" user "Package Geometry/Pastemask Bottom")
		(5 "F.SilkS" user "Ref Des/Silkscreen Top")
		(7 "B.SilkS" user "Ref Des/Silkscreen Bottom")
		(1 "F.Mask" user "Board Geometry/Soldermask Top")
		(3 "B.Mask" user "Board Geometry/Soldermask Bottom")
		(17 "Dwgs.User" user "User.Drawings")
		(19 "Cmts.User" user "User.Comments")
		(21 "Eco1.User" user "User.Eco1")
		(23 "Eco2.User" user "User.Eco2")
		(25 "Edge.Cuts" user "Board Geometry/Outline")
		(27 "Margin" user)
		(31 "F.CrtYd" user "Package Geometry/Place Bound Top")
		(29 "B.CrtYd" user "Package Geometry/Place Bound Bottom")
		(35 "F.Fab" user "Ref Des/Assembly Top")
		(33 "B.Fab" user "Ref Des/Assembly Bottom")
	)
	(footprint ""
		(layer "B.Cu")
		(at 87.884 -29.09316)
		(property "Reference" "SC877"
			(at 0 0 0)
			(layer "B.SilkS")
			(hide yes)
			(effects
				(font
					(size 1.27 1.27)
				)
				(justify mirror)
			)
		)
		(property "Value" "SCD01U16V2KX-3GP"
			(at -1.1811 -2.7051 0)
			(unlocked yes)
			(layer "B.Fab")
			(hide yes)
			(effects
				(font
					(size 1.016 1.016)
					(thickness 0.1524)
				)
				(justify mirror)
			)
		)
		(property "Device Type" "C402H22"
			(at -1.1811 -4.2291 0)
			(unlocked yes)
			(layer "B.Fab")
			(hide yes)
			(effects
				(font
					(size 1.016 1.016)
					(thickness 0.1524)
				)
				(justify mirror)
			)
		)
		(duplicate_pad_numbers_are_jumpers no)
		(fp_rect
			(start 0.4318 0.9525)
			(end -0.4318 -0.9525)
			(stroke
				(width 0)
				(type default)
			)
			(fill no)
			(layer "B.CrtYd")
		)
		(fp_rect
			(start 0.4318 0.9525)
			(end -0.4318 -0.9525)
			(stroke
				(width 0)
				(type default)
			)
			(fill no)
			(layer "B.Fab")
		)
		(pad "1" smd custom
			(at 0 -0.4445 180)
			(size 0.1524 0.1524)
			(layers "B.Cu" "B.Mask" "B.Paste")
			(net "CK_100M_EXP_SAS")
			(options
				(clearance outline)
				(anchor circle)
			)
			(primitives
				(gr_poly
					(pts
						(arc
							(start 0.3048 0.2032)
							(mid 0.275042 0.275042)
							(end 0.2032 0.3048)
						)
						(arc
							(start -0.2032 0.3048)
							(mid -0.275042 0.275042)
							(end -0.3048 0.2032)
						)
						(arc
							(start -0.3048 -0.2032)
							(mid -0.275042 -0.275042)
							(end -0.2032 -0.3048)
						)
						(arc
							(start 0.2032 -0.3048)
							(mid 0.275042 -0.275042)
							(end 0.3048 -0.2032)
						)
					)
					(width 0)
					(fill yes)
				)
			)
		)
		(pad "2" smd custom
			(at 0 0.4445 180)
			(size 0.1524 0.1524)
			(layers "B.Cu" "B.Mask" "B.Paste")
			(net "GND")
			(options
				(clearance outline)
				(anchor circle)
			)
			(primitives
				(gr_poly
					(pts
						(arc
							(start 0.3048 0.2032)
							(mid 0.275042 0.275042)
							(end 0.2032 0.3048)
						)
						(arc
							(start -0.2032 0.3048)
							(mid -0.275042 0.275042)
							(end -0.3048 0.2032)
						)
						(arc
							(start -0.3048 -0.2032)
							(mid -0.275042 -0.275042)
							(end -0.2032 -0.3048)
						)
						(arc
							(start 0.2032 -0.3048)
							(mid 0.275042 -0.275042)
							(end 0.3048 -0.2032)
						)
					)
					(width 0)
					(fill yes)
				)
			)
		)
	)
	(footprint ""
		(layer "B.Cu")
		(at 133.077966 -35.814 90)
		(property "Reference" "SC976"
			(at 0 0 90)
			(layer "B.SilkS")
			(hide yes)
			(effects
				(font
					(size 1.27 1.27)
				)
				(justify mirror)
			)
		)
		(property "Value" "SCD1U16V2KX-3GP"
			(at -1.1811 -2.7051 90)
			(unlocked yes)
			(layer "B.Fab")
			(hide yes)
			(effects
				(font
					(size 1.016 1.016)
					(thickness 0.1524)
				)
				(justify mirror)
			)
		)
		(property "Device Type" "C402H22"
			(at -1.1811 -4.2291 90)
			(unlocked yes)
			(layer "B.Fab")
			(hide yes)
			(effects
				(font
					(size 1.016 1.016)
					(thickness 0.1524)
				)
				(justify mirror)
			)
		)
		(duplicate_pad_numbers_are_jumpers no)
		(fp_rect
			(start 0.4318 0.9525)
			(end -0.4318 -0.9525)
			(stroke
				(width 0)
				(type default)
			)
			(fill no)
			(layer "B.CrtYd")
		)
		(fp_rect
			(start 0.4318 0.9525)
			(end -0.4318 -0.9525)
			(stroke
				(width 0)
				(type default)
			)
			(fill no)
			(layer "B.Fab")
		)
		(pad "1" smd custom
			(at 0 -0.4445 270)
			(size 0.1524 0.1524)
			(layers "B.Cu" "B.Mask" "B.Paste")
			(net "P1V8_C")
			(options
				(clearance outline)
				(anchor circle)
			)
			(primitives
				(gr_poly
					(pts
						(arc
							(start 0.3048 0.2032)
							(mid 0.275042 0.275042)
							(end 0.2032 0.3048)
						)
						(arc
							(start -0.2032 0.3048)
							(mid -0.275042 0.275042)
							(end -0.3048 0.2032)
						)
						(arc
							(start -0.3048 -0.2032)
							(mid -0.275042 -0.275042)
							(end -0.2032 -0.3048)
						)
						(arc
							(start 0.2032 -0.3048)
							(mid 0.275042 -0.275042)
							(end 0.3048 -0.2032)
						)
					)
					(width 0)
					(fill yes)
				)
			)
		)
		(pad "2" smd custom
			(at 0 0.4445 270)
			(size 0.1524 0.1524)
			(layers "B.Cu" "B.Mask" "B.Paste")
			(net "GND")
			(options
				(clearance outline)
				(anchor circle)
			)
			(primitives
				(gr_poly
					(pts
						(arc
							(start 0.3048 0.2032)
							(mid 0.275042 0.275042)
							(end 0.2032 0.3048)
						)
						(arc
							(start -0.2032 0.3048)
							(mid -0.275042 0.275042)
							(end -0.3048 0.2032)
						)
						(arc
							(start -0.3048 -0.2032)
							(mid -0.275042 -0.275042)
							(end -0.2032 -0.3048)
						)
						(arc
							(start 0.2032 -0.3048)
							(mid 0.275042 -0.275042)
							(end 0.3048 -0.2032)
						)
					)
					(width 0)
					(fill yes)
				)
			)
		)
	)
	(footprint ""
		(layer "B.Cu")
		(at 112.84077 -99.949)
		(property "Reference" "SC1136"
			(at 0 0 0)
			(layer "B.SilkS")
			(hide yes)
			(effects
				(font
					(size 1.27 1.27)
				)
				(justify mirror)
			)
		)
		(property "Value" "SCD1U6D3V1KX-GP"
			(at 2.8321 -1.7399 0)
			(unlocked yes)
			(layer "B.Fab")
			(hide yes)
			(effects
				(font
					(size 1.016 1.016)
					(thickness 0.1524)
				)
				(justify mirror)
			)
		)
		(property "Device Type" "C0201H13"
			(at 2.8321 -3.2639 0)
			(unlocked yes)
			(layer "B.Fab")
			(hide yes)
			(effects
				(font
					(size 1.016 1.016)
					(thickness 0.1524)
				)
				(justify mirror)
			)
		)
		(duplicate_pad_numbers_are_jumpers no)
		(fp_rect
			(start 0.2794 0.6477)
			(end -0.2794 -0.6477)
			(stroke
				(width 0)
				(type default)
			)
			(fill no)
			(layer "B.CrtYd")
		)
		(fp_rect
			(start 0.2794 0.6477)
			(end -0.2794 -0.6477)
			(stroke
				(width 0)
				(type default)
			)
			(fill no)
			(layer "B.Fab")
		)
		(pad "1" smd custom
			(at 0 -0.2794 180)
			(size 0.0762 0.0762)
			(layers "B.Cu" "B.Mask" "B.Paste")
			(net "GB_VDDH2")
			(options
				(clearance outline)
				(anchor circle)
			)
			(primitives
				(gr_poly
					(pts
						(arc
							(start 0.1524 0.127)
							(mid 0.137521 0.162921)
							(end 0.1016 0.1778)
						)
						(arc
							(start -0.1016 0.1778)
							(mid -0.137521 0.162921)
							(end -0.1524 0.127)
						)
						(arc
							(start -0.1524 -0.127)
							(mid -0.137521 -0.162921)
							(end -0.1016 -0.1778)
						)
						(arc
							(start 0.1016 -0.1778)
							(mid 0.137521 -0.162921)
							(end 0.1524 -0.127)
						)
					)
					(width 0)
					(fill yes)
				)
			)
		)
		(pad "2" smd custom
			(at 0 0.2794 180)
			(size 0.0762 0.0762)
			(layers "B.Cu" "B.Mask" "B.Paste")
			(net "GND")
			(options
				(clearance outline)
				(anchor circle)
			)
			(primitives
				(gr_poly
					(pts
						(arc
							(start 0.1524 0.127)
							(mid 0.137521 0.162921)
							(end 0.1016 0.1778)
						)
						(arc
							(start -0.1016 0.1778)
							(mid -0.137521 0.162921)
							(end -0.1524 0.127)
						)
						(arc
							(start -0.1524 -0.127)
							(mid -0.137521 -0.162921)
							(end -0.1016 -0.1778)
						)
						(arc
							(start 0.1016 -0.1778)
							(mid 0.137521 -0.162921)
							(end 0.1524 -0.127)
						)
					)
					(width 0)
					(fill yes)
				)
			)
		)
	)
	(footprint ""
		(layer "B.Cu")
		(at 163.957 -120.396 180)
		(property "Reference" "SR856"
			(at 0 0 0)
			(layer "B.SilkS")
			(hide yes)
			(effects
				(font
					(size 1.27 1.27)
				)
				(justify mirror)
			)
		)
		(property "Value" "1KR2J-1-GP"
			(at -0.064008 -3.993896 180)
			(unlocked yes)
			(layer "B.Fab")
			(hide yes)
			(effects
				(font
					(size 1.016 1.016)
					(thickness 0.1524)
				)
				(justify mirror)
			)
		)
		(property "Device Type" "R402H16"
			(at -0.064008 -5.517896 180)
			(unlocked yes)
			(layer "B.Fab")
			(hide yes)
			(effects
				(font
					(size 1.016 1.016)
					(thickness 0.1524)
				)
				(justify mirror)
			)
		)
		(duplicate_pad_numbers_are_jumpers no)
		(fp_line
			(start 0.508 -0.9398)
			(end 0.508 0.9398)
			(stroke
				(width 0.1524)
				(type default)
			)
			(layer "B.SilkS")
		)
		(fp_line
			(start -0.508 -0.9398)
			(end 0.508 -0.9398)
			(stroke
				(width 0.1524)
				(type default)
			)
			(layer "B.SilkS")
		)
		(fp_rect
			(start 0.508 0.9398)
			(end -0.508 -0.9398)
			(stroke
				(width 0)
				(type default)
			)
			(fill no)
			(layer "B.CrtYd")
		)
		(fp_rect
			(start 0.508 0.9398)
			(end -0.508 -0.9398)
			(stroke
				(width 0)
				(type default)
			)
			(fill no)
			(layer "B.Fab")
		)
		(pad "1" smd custom
			(at 0 -0.4445)
			(size 0.1397 0.1397)
			(layers "B.Cu" "B.Mask" "B.Paste")
			(net "EXP_RST")
			(options
				(clearance outline)
				(anchor circle)
			)
			(primitives
				(gr_poly
					(pts
						(arc
							(start -0.1778 0.2794)
							(mid -0.249642 0.249642)
							(end -0.2794 0.1778)
						)
						(arc
							(start -0.2794 -0.1778)
							(mid -0.249642 -0.249642)
							(end -0.1778 -0.2794)
						)
						(arc
							(start 0.1778 -0.2794)
							(mid 0.249642 -0.249642)
							(end 0.2794 -0.1778)
						)
						(arc
							(start 0.2794 0.1778)
							(mid 0.249642 0.249642)
							(end 0.1778 0.2794)
						)
					)
					(width 0)
					(fill yes)
				)
			)
		)
		(pad "2" smd custom
			(at 0 0.4445)
			(size 0.1397 0.1397)
			(layers "B.Cu" "B.Mask" "B.Paste")
			(net "P1V8_E")
			(options
				(clearance outline)
				(anchor circle)
			)
			(primitives
				(gr_poly
					(pts
						(arc
							(start -0.1778 0.2794)
							(mid -0.249642 0.249642)
							(end -0.2794 0.1778)
						)
						(arc
							(start -0.2794 -0.1778)
							(mid -0.249642 -0.249642)
							(end -0.1778 -0.2794)
						)
						(arc
							(start 0.1778 -0.2794)
							(mid 0.249642 -0.249642)
							(end 0.2794 -0.1778)
						)
						(arc
							(start 0.2794 0.1778)
							(mid 0.249642 0.249642)
							(end 0.1778 0.2794)
						)
					)
					(width 0)
					(fill yes)
				)
			)
		)
	)
	(footprint ""
		(layer "B.Cu")
		(at 107.995212 -219.456 -90)
		(property "Reference" "SC1293"
			(at 0 0 90)
			(layer "B.SilkS")
			(hide yes)
			(effects
				(font
					(size 1.27 1.27)
				)
				(justify mirror)
			)
		)
		(property "Value" "SCD1U16V2KX-3GP"
			(at -1.1811 -2.7051 270)
			(unlocked yes)
			(layer "B.Fab")
			(hide yes)
			(effects
				(font
					(size 1.016 1.016)
					(thickness 0.1524)
				)
				(justify mirror)
			)
		)
		(property "Device Type" "C402H22"
			(at -1.1811 -4.2291 270)
			(unlocked yes)
			(layer "B.Fab")
			(hide yes)
			(effects
				(font
					(size 1.016 1.016)
					(thickness 0.1524)
				)
				(justify mirror)
			)
		)
		(duplicate_pad_numbers_are_jumpers no)
		(fp_rect
			(start 0.4318 0.9525)
			(end -0.4318 -0.9525)
			(stroke
				(width 0)
				(type default)
			)
			(fill no)
			(layer "B.CrtYd")
		)
		(fp_rect
			(start 0.4318 0.9525)
			(end -0.4318 -0.9525)
			(stroke
				(width 0)
				(type default)
			)
			(fill no)
			(layer "B.Fab")
		)
		(pad "1" smd custom
			(at 0 -0.4445 90)
			(size 0.1524 0.1524)
			(layers "B.Cu" "B.Mask" "B.Paste")
			(net "1.2V_REDV")
			(options
				(clearance outline)
				(anchor circle)
			)
			(primitives
				(gr_poly
					(pts
						(arc
							(start 0.3048 0.2032)
							(mid 0.275042 0.275042)
							(end 0.2032 0.3048)
						)
						(arc
							(start -0.2032 0.3048)
							(mid -0.275042 0.275042)
							(end -0.3048 0.2032)
						)
						(arc
							(start -0.3048 -0.2032)
							(mid -0.275042 -0.275042)
							(end -0.2032 -0.3048)
						)
						(arc
							(start 0.2032 -0.3048)
							(mid 0.275042 -0.275042)
							(end 0.3048 -0.2032)
						)
					)
					(width 0)
					(fill yes)
				)
			)
		)
		(pad "2" smd custom
			(at 0 0.4445 90)
			(size 0.1524 0.1524)
			(layers "B.Cu" "B.Mask" "B.Paste")
			(net "GND")
			(options
				(clearance outline)
				(anchor circle)
			)
			(primitives
				(gr_poly
					(pts
						(arc
							(start 0.3048 0.2032)
							(mid 0.275042 0.275042)
							(end 0.2032 0.3048)
						)
						(arc
							(start -0.2032 0.3048)
							(mid -0.275042 0.275042)
							(end -0.3048 0.2032)
						)
						(arc
							(start -0.3048 -0.2032)
							(mid -0.275042 -0.275042)
							(end -0.2032 -0.3048)
						)
						(arc
							(start 0.2032 -0.3048)
							(mid 0.275042 -0.275042)
							(end 0.3048 -0.2032)
						)
					)
					(width 0)
					(fill yes)
				)
			)
		)
	)
	(footprint ""
		(layer "B.Cu")
		(at 180.013864 -32.076136 90)
		(property "Reference" "C222"
			(at 0 0 90)
			(layer "B.SilkS")
			(hide yes)
			(effects
				(font
					(size 1.27 1.27)
				)
				(justify mirror)
			)
		)
		(property "Value" "SCD01U16V2KX-3GP"
			(at -1.1811 -2.7051 90)
			(unlocked yes)
			(layer "B.Fab")
			(hide yes)
			(effects
				(font
					(size 1.016 1.016)
					(thickness 0.1524)
				)
				(justify mirror)
			)
		)
		(property "Device Type" "C402H22"
			(at -1.1811 -4.2291 90)
			(unlocked yes)
			(layer "B.Fab")
			(hide yes)
			(effects
				(font
					(size 1.016 1.016)
					(thickness 0.1524)
				)
				(justify mirror)
			)
		)
		(duplicate_pad_numbers_are_jumpers no)
		(fp_rect
			(start 0.4318 0.9525)
			(end -0.4318 -0.9525)
			(stroke
				(width 0)
				(type default)
			)
			(fill no)
			(layer "B.CrtYd")
		)
		(fp_rect
			(start 0.4318 0.9525)
			(end -0.4318 -0.9525)
			(stroke
				(width 0)
				(type default)
			)
			(fill no)
			(layer "B.Fab")
		)
		(pad "1" smd custom
			(at 0 -0.4445 270)
			(size 0.1524 0.1524)
			(layers "B.Cu" "B.Mask" "B.Paste")
			(net "PHY_AVDD")
			(options
				(clearance outline)
				(anchor circle)
			)
			(primitives
				(gr_poly
					(pts
						(arc
							(start 0.3048 0.2032)
							(mid 0.275042 0.275042)
							(end 0.2032 0.3048)
						)
						(arc
							(start -0.2032 0.3048)
							(mid -0.275042 0.275042)
							(end -0.3048 0.2032)
						)
						(arc
							(start -0.3048 -0.2032)
							(mid -0.275042 -0.275042)
							(end -0.2032 -0.3048)
						)
						(arc
							(start 0.2032 -0.3048)
							(mid 0.275042 -0.275042)
							(end 0.3048 -0.2032)
						)
					)
					(width 0)
					(fill yes)
				)
			)
		)
		(pad "2" smd custom
			(at 0 0.4445 270)
			(size 0.1524 0.1524)
			(layers "B.Cu" "B.Mask" "B.Paste")
			(net "GND")
			(options
				(clearance outline)
				(anchor circle)
			)
			(primitives
				(gr_poly
					(pts
						(arc
							(start 0.3048 0.2032)
							(mid 0.275042 0.275042)
							(end 0.2032 0.3048)
						)
						(arc
							(start -0.2032 0.3048)
							(mid -0.275042 0.275042)
							(end -0.3048 0.2032)
						)
						(arc
							(start -0.3048 -0.2032)
							(mid -0.275042 -0.275042)
							(end -0.2032 -0.3048)
						)
						(arc
							(start 0.2032 -0.3048)
							(mid 0.275042 -0.275042)
							(end 0.3048 -0.2032)
						)
					)
					(width 0)
					(fill yes)
				)
			)
		)
	)
	(footprint ""
		(layer "B.Cu")
		(at 115.043966 -34.163)
		(property "Reference" "STP94"
			(at 0 0 0)
			(layer "B.SilkS")
			(hide yes)
			(effects
				(font
					(size 1.27 1.27)
				)
				(justify mirror)
			)
		)
		(property "Value" "TPAD28"
			(at -0.0127 -1.8034 0)
			(unlocked yes)
			(layer "B.Fab")
			(hide yes)
			(effects
				(font
					(size 1.016 1.016)
					(thickness 0.1524)
				)
				(justify mirror)
			)
		)
		(property "Device Type" "TPAD28"
			(at -0.0127 -3.3274 0)
			(unlocked yes)
			(layer "B.Fab")
			(hide yes)
			(effects
				(font
					(size 1.016 1.016)
					(thickness 0.1524)
				)
				(justify mirror)
			)
		)
		(duplicate_pad_numbers_are_jumpers no)
		(fp_poly
			(pts
				(arc
					(start 0.3556 0)
					(mid -0.3556 0)
					(end 0.3556 0)
				)
			)
			(stroke
				(width 0)
				(type default)
			)
			(fill no)
			(layer "B.CrtYd")
		)
		(fp_poly
			(pts
				(arc
					(start 0.6096 0)
					(mid -0.6096 0)
					(end 0.6096 0)
				)
			)
			(stroke
				(width 0)
				(type default)
			)
			(fill no)
			(layer "B.Fab")
		)
		(pad "1" smd circle
			(at 0 0 180)
			(size 0.7112 0.7112)
			(layers "B.Cu" "B.Mask" "B.Paste")
			(net "IOC_GPIO_0")
		)
	)
	(footprint ""
		(layer "B.Cu")
		(at 49.60493 -76.634086)
		(property "Reference" "TP186"
			(at 0 0 0)
			(layer "B.SilkS")
			(hide yes)
			(effects
				(font
					(size 1.27 1.27)
				)
				(justify mirror)
			)
		)
		(property "Value" "TPAD32-GP"
			(at 0 -3.166364 0)
			(unlocked yes)
			(layer "B.Fab")
			(hide yes)
			(effects
				(font
					(size 1.016 1.016)
					(thickness 0.1524)
				)
				(justify mirror)
			)
		)
		(property "Device Type" "TPAD32"
			(at 0 -4.690618 0)
			(unlocked yes)
			(layer "B.Fab")
			(hide yes)
			(effects
				(font
					(size 1.016 1.016)
					(thickness 0.1524)
				)
				(justify mirror)
			)
		)
		(duplicate_pad_numbers_are_jumpers no)
		(fp_poly
			(pts
				(arc
					(start 0.4064 0)
					(mid -0.4064 0)
					(end 0.4064 0)
				)
			)
			(stroke
				(width 0)
				(type default)
			)
			(fill no)
			(layer "B.CrtYd")
		)
		(fp_poly
			(pts
				(arc
					(start 0.7112 0)
					(mid -0.7112 0)
					(end 0.7112 0)
				)
			)
			(stroke
				(width 0)
				(type default)
			)
			(fill no)
			(layer "B.Fab")
		)
		(pad "1" smd circle
			(at 0 0 180)
			(size 0.8128 0.8128)
			(layers "B.Cu" "B.Mask" "B.Paste")
			(net "INT_CONN_A_SB5")
		)
	)
	(footprint ""
		(layer "B.Cu")
		(at 105.16616 -35.306 -90)
		(property "Reference" "SC998"
			(at 0 0 90)
			(layer "B.SilkS")
			(hide yes)
			(effects
				(font
					(size 1.27 1.27)
				)
				(justify mirror)
			)
		)
		(property "Value" "SCD1U16V2KX-3GP"
			(at -1.1811 -2.7051 270)
			(unlocked yes)
			(layer "B.Fab")
			(hide yes)
			(effects
				(font
					(size 1.016 1.016)
					(thickness 0.1524)
				)
				(justify mirror)
			)
		)
		(property "Device Type" "C402H22"
			(at -1.1811 -4.2291 270)
			(unlocked yes)
			(layer "B.Fab")
			(hide yes)
			(effects
				(font
					(size 1.016 1.016)
					(thickness 0.1524)
				)
				(justify mirror)
			)
		)
		(duplicate_pad_numbers_are_jumpers no)
		(fp_rect
			(start 0.4318 0.9525)
			(end -0.4318 -0.9525)
			(stroke
				(width 0)
				(type default)
			)
			(fill no)
			(layer "B.CrtYd")
		)
		(fp_rect
			(start 0.4318 0.9525)
			(end -0.4318 -0.9525)
			(stroke
				(width 0)
				(type default)
			)
			(fill no)
			(layer "B.Fab")
		)
		(pad "1" smd custom
			(at 0 -0.4445 90)
			(size 0.1524 0.1524)
			(layers "B.Cu" "B.Mask" "B.Paste")
			(net "P1V8_C")
			(options
				(clearance outline)
				(anchor circle)
			)
			(primitives
				(gr_poly
					(pts
						(arc
							(start 0.3048 0.2032)
							(mid 0.275042 0.275042)
							(end 0.2032 0.3048)
						)
						(arc
							(start -0.2032 0.3048)
							(mid -0.275042 0.275042)
							(end -0.3048 0.2032)
						)
						(arc
							(start -0.3048 -0.2032)
							(mid -0.275042 -0.275042)
							(end -0.2032 -0.3048)
						)
						(arc
							(start 0.2032 -0.3048)
							(mid 0.275042 -0.275042)
							(end 0.3048 -0.2032)
						)
					)
					(width 0)
					(fill yes)
				)
			)
		)
		(pad "2" smd custom
			(at 0 0.4445 90)
			(size 0.1524 0.1524)
			(layers "B.Cu" "B.Mask" "B.Paste")
			(net "GND")
			(options
				(clearance outline)
				(anchor circle)
			)
			(primitives
				(gr_poly
					(pts
						(arc
							(start 0.3048 0.2032)
							(mid 0.275042 0.275042)
							(end 0.2032 0.3048)
						)
						(arc
							(start -0.2032 0.3048)
							(mid -0.275042 0.275042)
							(end -0.3048 0.2032)
						)
						(arc
							(start -0.3048 -0.2032)
							(mid -0.275042 -0.275042)
							(end -0.2032 -0.3048)
						)
						(arc
							(start 0.2032 -0.3048)
							(mid 0.275042 -0.275042)
							(end 0.3048 -0.2032)
						)
					)
					(width 0)
					(fill yes)
				)
			)
		)
	)
)
